(kicad_pcb
	(version 20260206)
	(generator "pcbnew")
	(generator_version "10.0")
	(general
		(thickness 1.6)
		(legacy_teardrops no)
	)
	(paper "A4")
	(title_block
		(title "panther-plus-userver — 13130-1b_20150205.brd")
		(comment 1 "Honey Badger (Wiwynn) / footprint 894 of 1509 (DIMM1), pads 16-22 of 210")
	)
	(layers
		(0 "F.Cu" signal "TOP")
		(4 "In1.Cu" signal "L2")
		(6 "In2.Cu" signal "L3")
		(8 "In3.Cu" signal "L4")
		(10 "In4.Cu" signal "L5")
		(12 "In5.Cu" signal "L6")
		(14 "In6.Cu" signal "L7")
		(16 "In7.Cu" signal "L8")
		(18 "In8.Cu" signal "L9")
		(20 "In9.Cu" signal "L10")
		(22 "In10.Cu" signal "L11")
		(2 "B.Cu" signal "BOTTOM")
		(9 "F.Adhes" user "F.Adhesive")
		(11 "B.Adhes" user "B.Adhesive")
		(13 "F.Paste" user "Package Geometry/Pastemask Top")
		(15 "B.Paste" user "Package Geometry/Pastemask Bottom")
		(5 "F.SilkS" user "Ref Des/Silkscreen Top")
		(7 "B.SilkS" user "Ref Des/Silkscreen Bottom")
		(1 "F.Mask" user "Board Geometry/Soldermask Top")
		(3 "B.Mask" user "Board Geometry/Soldermask Bottom")
		(17 "Dwgs.User" user "User.Drawings")
		(19 "Cmts.User" user "User.Comments")
		(21 "Eco1.User" user "User.Eco1")
		(23 "Eco2.User" user "User.Eco2")
		(25 "Edge.Cuts" user "Board Geometry/Outline")
		(27 "Margin" user)
		(31 "F.CrtYd" user "Package Geometry/Place Bound Top")
		(29 "B.CrtYd" user "Package Geometry/Place Bound Bottom")
		(35 "F.Fab" user "Ref Des/Assembly Top")
		(33 "B.Fab" user "Ref Des/Assembly Bottom")
	)
	(footprint ""
		(layer "B.Cu")
		(at 158.500064 -66.699892 180)
		(property "Reference" "DIMM1"
			(at 0 0 0)
			(layer "B.SilkS")
			(hide yes)
			(effects
				(font
					(size 1.27 1.27)
				)
				(justify mirror)
			)
		)
		(property "Value" "DDR3-204P-142-COLAY-1-GP-U"
			(at 41.312338 -16.676878 180)
			(unlocked yes)
			(layer "B.Fab")
			(hide yes)
			(effects
				(font
					(size 1.016 1.016)
					(thickness 0.1524)
				)
				(justify mirror)
			)
		)
		(property "Device Type" "AS0A626-J8R6-7H-COLAY-1"
			(at 41.312338 -18.200878 180)
			(unlocked yes)
			(layer "B.Fab")
			(hide yes)
			(effects
				(font
					(size 1.016 1.016)
					(thickness 0.1524)
				)
				(justify mirror)
			)
		)
		(duplicate_pad_numbers_are_jumpers no)
		(pad "14" smd custom
			(at -27.750008 4.100068)
			(size 0.1143 0.1143)
			(layers "B.Cu" "B.Mask" "B.Paste")
			(net "GND")
			(options
				(clearance outline)
				(anchor circle)
			)
			(primitives
				(gr_poly
					(pts
						(xy 0 -0.9017) (xy -0.03175 -0.89916) (xy -0.0635 -0.889) (xy -0.09144 -0.87376) (xy -0.11684 -0.85344)
						(xy -0.13716 -0.82804) (xy -0.1524 -0.8001) (xy -0.16256 -0.76835) (xy -0.1651 -0.7366) (xy -0.1651 0.13462)
						(xy -0.17272 0.14224) (xy -0.19812 0.1778) (xy -0.2032 0.18796) (xy -0.20701 0.19685) (xy -0.21209 0.20701)
						(xy -0.2159 0.21717) (xy -0.21844 0.22733) (xy -0.22225 0.23876) (xy -0.22352 0.24892) (xy -0.22606 0.25908)
						(xy -0.22733 0.27051) (xy -0.22733 0.28067) (xy -0.2286 0.2921) (xy -0.22733 0.30353) (xy -0.22733 0.31369)
						(xy -0.22606 0.32512) (xy -0.22352 0.33528) (xy -0.22225 0.34544) (xy -0.21844 0.35687) (xy -0.2159 0.36703)
						(xy -0.21209 0.37719) (xy -0.20701 0.38735) (xy -0.2032 0.39624) (xy -0.19812 0.4064) (xy -0.17272 0.44196)
						(xy -0.1651 0.44958) (xy -0.1651 0.7366) (xy -0.16256 0.76835) (xy -0.1524 0.8001) (xy -0.13716 0.82804)
						(xy -0.11684 0.85344) (xy -0.09144 0.87376) (xy -0.0635 0.889) (xy -0.03175 0.89916) (xy 0 0.9017)
						(xy 0.03175 0.89916) (xy 0.0635 0.889) (xy 0.09144 0.87376) (xy 0.11684 0.85344) (xy 0.13716 0.82804)
						(xy 0.1524 0.8001) (xy 0.16256 0.76835) (xy 0.1651 0.7366) (xy 0.1651 0.44958) (xy 0.17272 0.44196)
						(xy 0.19812 0.4064) (xy 0.2032 0.39624) (xy 0.20701 0.38735) (xy 0.21209 0.37719) (xy 0.2159 0.36703)
						(xy 0.21844 0.35687) (xy 0.22225 0.34544) (xy 0.22352 0.33528) (xy 0.22606 0.32512) (xy 0.22733 0.31369)
						(xy 0.22733 0.30353) (xy 0.2286 0.2921) (xy 0.22733 0.28067) (xy 0.22733 0.27051) (xy 0.22606 0.25908)
						(xy 0.22352 0.24892) (xy 0.22225 0.23876) (xy 0.21844 0.22733) (xy 0.2159 0.21717) (xy 0.21209 0.20701)
						(xy 0.20701 0.19685) (xy 0.2032 0.18796) (xy 0.19812 0.1778) (xy 0.17272 0.14224) (xy 0.1651 0.13462)
						(xy 0.1651 -0.7366) (xy 0.16256 -0.76835) (xy 0.1524 -0.8001) (xy 0.13716 -0.82804) (xy 0.11684 -0.85344)
						(xy 0.09144 -0.87376) (xy 0.0635 -0.889) (xy 0.03175 -0.89916)
					)
					(width 0)
					(fill yes)
				)
			)
		)
		(pad "15" smd custom
			(at -27.450034 -4.100068)
			(size 0.1143 0.1143)
			(layers "B.Cu" "B.Mask" "B.Paste")
			(net "M_A_DQ3")
			(options
				(clearance outline)
				(anchor circle)
			)
			(primitives
				(gr_poly
					(pts
						(xy 0 -0.9017) (xy -0.03175 -0.89916) (xy -0.0635 -0.889) (xy -0.09144 -0.87376) (xy -0.11684 -0.85344)
						(xy -0.13716 -0.82804) (xy -0.1524 -0.8001) (xy -0.16256 -0.76835) (xy -0.1651 -0.7366) (xy -0.1651 -0.19685)
						(xy -0.17272 -0.18923) (xy -0.17907 -0.18034) (xy -0.18669 -0.17145) (xy -0.19177 -0.16256) (xy -0.19812 -0.15367)
						(xy -0.20828 -0.13335) (xy -0.21971 -0.10287) (xy -0.22225 -0.09271) (xy -0.22479 -0.08128) (xy -0.22606 -0.07112)
						(xy -0.2286 -0.05969) (xy -0.2286 -0.01651) (xy -0.22606 -0.00508) (xy -0.22479 0.00508) (xy -0.22225 0.01651)
						(xy -0.21971 0.02667) (xy -0.20828 0.05715) (xy -0.19812 0.07747) (xy -0.19177 0.08636) (xy -0.18669 0.09525)
						(xy -0.17907 0.10414) (xy -0.17272 0.11303) (xy -0.1651 0.12065) (xy -0.1651 0.7366) (xy -0.16256 0.76835)
						(xy -0.1524 0.8001) (xy -0.13716 0.82804) (xy -0.11684 0.85344) (xy -0.09144 0.87376) (xy -0.0635 0.889)
						(xy -0.03175 0.89916) (xy 0 0.9017) (xy 0.03175 0.89916) (xy 0.0635 0.889) (xy 0.09144 0.87376)
						(xy 0.11684 0.85344) (xy 0.13716 0.82804) (xy 0.1524 0.8001) (xy 0.16256 0.76835) (xy 0.1651 0.7366)
						(xy 0.1651 0.11938) (xy 0.17272 0.11176) (xy 0.19812 0.0762) (xy 0.2032 0.06604) (xy 0.20701 0.05715)
						(xy 0.21209 0.04699) (xy 0.2159 0.03683) (xy 0.21844 0.02667) (xy 0.22225 0.01524) (xy 0.22352 0.00508)
						(xy 0.22606 -0.00508) (xy 0.22733 -0.01651) (xy 0.22733 -0.02667) (xy 0.2286 -0.0381) (xy 0.22733 -0.04953)
						(xy 0.22733 -0.05969) (xy 0.22606 -0.07112) (xy 0.22352 -0.08128) (xy 0.22225 -0.09144) (xy 0.21844 -0.10287)
						(xy 0.2159 -0.11303) (xy 0.21209 -0.12319) (xy 0.20701 -0.13335) (xy 0.2032 -0.14224) (xy 0.19812 -0.1524)
						(xy 0.17272 -0.18796) (xy 0.1651 -0.19558) (xy 0.1651 -0.7366) (xy 0.16256 -0.76835) (xy 0.1524 -0.8001)
						(xy 0.13716 -0.82804) (xy 0.11684 -0.85344) (xy 0.09144 -0.87376) (xy 0.0635 -0.889) (xy 0.03175 -0.89916)
					)
					(width 0)
					(fill yes)
				)
			)
		)
		(pad "16" smd custom
			(at -27.15006 4.100068)
			(size 0.1143 0.1143)
			(layers "B.Cu" "B.Mask" "B.Paste")
			(net "M_A_DQ6")
			(options
				(clearance outline)
				(anchor circle)
			)
			(primitives
				(gr_poly
					(pts
						(xy 0 -0.9017) (xy -0.03175 -0.89916) (xy -0.0635 -0.889) (xy -0.09144 -0.87376) (xy -0.11684 -0.85344)
						(xy -0.13716 -0.82804) (xy -0.1524 -0.8001) (xy -0.16256 -0.76835) (xy -0.1651 -0.7366) (xy -0.1651 -0.11938)
						(xy -0.17272 -0.11176) (xy -0.19812 -0.0762) (xy -0.2032 -0.06604) (xy -0.20701 -0.05715) (xy -0.21209 -0.04699)
						(xy -0.2159 -0.03683) (xy -0.21844 -0.02667) (xy -0.22225 -0.01524) (xy -0.22352 -0.00508) (xy -0.22606 0.00508)
						(xy -0.22733 0.01651) (xy -0.22733 0.02667) (xy -0.2286 0.0381) (xy -0.22733 0.04953) (xy -0.22733 0.05969)
						(xy -0.22606 0.07112) (xy -0.22352 0.08128) (xy -0.22225 0.09144) (xy -0.21844 0.10287) (xy -0.2159 0.11303)
						(xy -0.21209 0.12319) (xy -0.20701 0.13335) (xy -0.2032 0.14224) (xy -0.19812 0.1524) (xy -0.17272 0.18796)
						(xy -0.1651 0.19558) (xy -0.1651 0.7366) (xy -0.16256 0.76835) (xy -0.1524 0.8001) (xy -0.13716 0.82804)
						(xy -0.11684 0.85344) (xy -0.09144 0.87376) (xy -0.0635 0.889) (xy -0.03175 0.89916) (xy 0 0.9017)
						(xy 0.03175 0.89916) (xy 0.0635 0.889) (xy 0.09144 0.87376) (xy 0.11684 0.85344) (xy 0.13716 0.82804)
						(xy 0.1524 0.8001) (xy 0.16256 0.76835) (xy 0.1651 0.7366) (xy 0.1651 0.19685) (xy 0.17272 0.18923)
						(xy 0.17907 0.18034) (xy 0.18669 0.17145) (xy 0.19177 0.16256) (xy 0.19812 0.15367) (xy 0.20828 0.13335)
						(xy 0.21971 0.10287) (xy 0.22225 0.09271) (xy 0.22479 0.08128) (xy 0.22606 0.07112) (xy 0.2286 0.05969)
						(xy 0.2286 0.01651) (xy 0.22606 0.00508) (xy 0.22479 -0.00508) (xy 0.22225 -0.01651) (xy 0.21971 -0.02667)
						(xy 0.20828 -0.05715) (xy 0.19812 -0.07747) (xy 0.19177 -0.08636) (xy 0.18669 -0.09525) (xy 0.17907 -0.10414)
						(xy 0.17272 -0.11303) (xy 0.1651 -0.12065) (xy 0.1651 -0.7366) (xy 0.16256 -0.76835) (xy 0.1524 -0.8001)
						(xy 0.13716 -0.82804) (xy 0.11684 -0.85344) (xy 0.09144 -0.87376) (xy 0.0635 -0.889) (xy 0.03175 -0.89916)
					)
					(width 0)
					(fill yes)
				)
			)
		)
		(pad "17" smd custom
			(at -26.850086 -4.100068)
			(size 0.1143 0.1143)
			(layers "B.Cu" "B.Mask" "B.Paste")
			(net "GND")
			(options
				(clearance outline)
				(anchor circle)
			)
			(primitives
				(gr_poly
					(pts
						(xy 0 -0.9017) (xy -0.03175 -0.89916) (xy -0.0635 -0.889) (xy -0.09144 -0.87376) (xy -0.11684 -0.85344)
						(xy -0.13716 -0.82804) (xy -0.1524 -0.8001) (xy -0.16256 -0.76835) (xy -0.1651 -0.7366) (xy -0.1651 -0.44958)
						(xy -0.17272 -0.44196) (xy -0.19812 -0.4064) (xy -0.2032 -0.39624) (xy -0.20701 -0.38735) (xy -0.21209 -0.37719)
						(xy -0.2159 -0.36703) (xy -0.21844 -0.35687) (xy -0.22225 -0.34544) (xy -0.22352 -0.33528) (xy -0.22606 -0.32512)
						(xy -0.22733 -0.31369) (xy -0.22733 -0.30353) (xy -0.2286 -0.2921) (xy -0.22733 -0.28067) (xy -0.22733 -0.27051)
						(xy -0.22606 -0.25908) (xy -0.22352 -0.24892) (xy -0.22225 -0.23876) (xy -0.21844 -0.22733) (xy -0.2159 -0.21717)
						(xy -0.21209 -0.20701) (xy -0.20701 -0.19685) (xy -0.2032 -0.18796) (xy -0.19812 -0.1778) (xy -0.17272 -0.14224)
						(xy -0.1651 -0.13462) (xy -0.1651 0.7366) (xy -0.16256 0.76835) (xy -0.1524 0.8001) (xy -0.13716 0.82804)
						(xy -0.11684 0.85344) (xy -0.09144 0.87376) (xy -0.0635 0.889) (xy -0.03175 0.89916) (xy 0 0.9017)
						(xy 0.03175 0.89916) (xy 0.0635 0.889) (xy 0.09144 0.87376) (xy 0.11684 0.85344) (xy 0.13716 0.82804)
						(xy 0.1524 0.8001) (xy 0.16256 0.76835) (xy 0.1651 0.7366) (xy 0.1651 -0.13462) (xy 0.17272 -0.14224)
						(xy 0.19812 -0.1778) (xy 0.2032 -0.18796) (xy 0.20701 -0.19685) (xy 0.21209 -0.20701) (xy 0.2159 -0.21717)
						(xy 0.21844 -0.22733) (xy 0.22225 -0.23876) (xy 0.22352 -0.24892) (xy 0.22606 -0.25908) (xy 0.22733 -0.27051)
						(xy 0.22733 -0.28067) (xy 0.2286 -0.2921) (xy 0.22733 -0.30353) (xy 0.22733 -0.31369) (xy 0.22606 -0.32512)
						(xy 0.22352 -0.33528) (xy 0.22225 -0.34544) (xy 0.21844 -0.35687) (xy 0.2159 -0.36703) (xy 0.21209 -0.37719)
						(xy 0.20701 -0.38735) (xy 0.2032 -0.39624) (xy 0.19812 -0.4064) (xy 0.17272 -0.44196) (xy 0.1651 -0.44958)
						(xy 0.1651 -0.7366) (xy 0.16256 -0.76835) (xy 0.1524 -0.8001) (xy 0.13716 -0.82804) (xy 0.11684 -0.85344)
						(xy 0.09144 -0.87376) (xy 0.0635 -0.889) (xy 0.03175 -0.89916)
					)
					(width 0)
					(fill yes)
				)
			)
		)
		(pad "18" smd custom
			(at -26.550112 4.100068)
			(size 0.1143 0.1143)
			(layers "B.Cu" "B.Mask" "B.Paste")
			(net "M_A_DQ7")
			(options
				(clearance outline)
				(anchor circle)
			)
			(primitives
				(gr_poly
					(pts
						(xy 0 -0.9017) (xy -0.03175 -0.89916) (xy -0.0635 -0.889) (xy -0.09144 -0.87376) (xy -0.11684 -0.85344)
						(xy -0.13716 -0.82804) (xy -0.1524 -0.8001) (xy -0.16256 -0.76835) (xy -0.1651 -0.7366) (xy -0.1651 0.13462)
						(xy -0.17272 0.14224) (xy -0.19812 0.1778) (xy -0.2032 0.18796) (xy -0.20701 0.19685) (xy -0.21209 0.20701)
						(xy -0.2159 0.21717) (xy -0.21844 0.22733) (xy -0.22225 0.23876) (xy -0.22352 0.24892) (xy -0.22606 0.25908)
						(xy -0.22733 0.27051) (xy -0.22733 0.28067) (xy -0.2286 0.2921) (xy -0.22733 0.30353) (xy -0.22733 0.31369)
						(xy -0.22606 0.32512) (xy -0.22352 0.33528) (xy -0.22225 0.34544) (xy -0.21844 0.35687) (xy -0.2159 0.36703)
						(xy -0.21209 0.37719) (xy -0.20701 0.38735) (xy -0.2032 0.39624) (xy -0.19812 0.4064) (xy -0.17272 0.44196)
						(xy -0.1651 0.44958) (xy -0.1651 0.7366) (xy -0.16256 0.76835) (xy -0.1524 0.8001) (xy -0.13716 0.82804)
						(xy -0.11684 0.85344) (xy -0.09144 0.87376) (xy -0.0635 0.889) (xy -0.03175 0.89916) (xy 0 0.9017)
						(xy 0.03175 0.89916) (xy 0.0635 0.889) (xy 0.09144 0.87376) (xy 0.11684 0.85344) (xy 0.13716 0.82804)
						(xy 0.1524 0.8001) (xy 0.16256 0.76835) (xy 0.1651 0.7366) (xy 0.1651 0.44958) (xy 0.17272 0.44196)
						(xy 0.19812 0.4064) (xy 0.2032 0.39624) (xy 0.20701 0.38735) (xy 0.21209 0.37719) (xy 0.2159 0.36703)
						(xy 0.21844 0.35687) (xy 0.22225 0.34544) (xy 0.22352 0.33528) (xy 0.22606 0.32512) (xy 0.22733 0.31369)
						(xy 0.22733 0.30353) (xy 0.2286 0.2921) (xy 0.22733 0.28067) (xy 0.22733 0.27051) (xy 0.22606 0.25908)
						(xy 0.22352 0.24892) (xy 0.22225 0.23876) (xy 0.21844 0.22733) (xy 0.2159 0.21717) (xy 0.21209 0.20701)
						(xy 0.20701 0.19685) (xy 0.2032 0.18796) (xy 0.19812 0.1778) (xy 0.17272 0.14224) (xy 0.1651 0.13462)
						(xy 0.1651 -0.7366) (xy 0.16256 -0.76835) (xy 0.1524 -0.8001) (xy 0.13716 -0.82804) (xy 0.11684 -0.85344)
						(xy 0.09144 -0.87376) (xy 0.0635 -0.889) (xy 0.03175 -0.89916)
					)
					(width 0)
					(fill yes)
				)
			)
		)
		(pad "19" smd custom
			(at -26.249884 -4.100068)
			(size 0.1143 0.1143)
			(layers "B.Cu" "B.Mask" "B.Paste")
			(net "M_A_DQ8")
			(options
				(clearance outline)
				(anchor circle)
			)
			(primitives
				(gr_poly
					(pts
						(xy 0 -0.9017) (xy -0.03175 -0.89916) (xy -0.0635 -0.889) (xy -0.09144 -0.87376) (xy -0.11684 -0.85344)
						(xy -0.13716 -0.82804) (xy -0.1524 -0.8001) (xy -0.16256 -0.76835) (xy -0.1651 -0.7366) (xy -0.1651 -0.19685)
						(xy -0.17272 -0.18923) (xy -0.17907 -0.18034) (xy -0.18669 -0.17145) (xy -0.19177 -0.16256) (xy -0.19812 -0.15367)
						(xy -0.20828 -0.13335) (xy -0.21971 -0.10287) (xy -0.22225 -0.09271) (xy -0.22479 -0.08128) (xy -0.22606 -0.07112)
						(xy -0.2286 -0.05969) (xy -0.2286 -0.01651) (xy -0.22606 -0.00508) (xy -0.22479 0.00508) (xy -0.22225 0.01651)
						(xy -0.21971 0.02667) (xy -0.20828 0.05715) (xy -0.19812 0.07747) (xy -0.19177 0.08636) (xy -0.18669 0.09525)
						(xy -0.17907 0.10414) (xy -0.17272 0.11303) (xy -0.1651 0.12065) (xy -0.1651 0.7366) (xy -0.16256 0.76835)
						(xy -0.1524 0.8001) (xy -0.13716 0.82804) (xy -0.11684 0.85344) (xy -0.09144 0.87376) (xy -0.0635 0.889)
						(xy -0.03175 0.89916) (xy 0 0.9017) (xy 0.03175 0.89916) (xy 0.0635 0.889) (xy 0.09144 0.87376)
						(xy 0.11684 0.85344) (xy 0.13716 0.82804) (xy 0.1524 0.8001) (xy 0.16256 0.76835) (xy 0.1651 0.7366)
						(xy 0.1651 0.11938) (xy 0.17272 0.11176) (xy 0.19812 0.0762) (xy 0.2032 0.06604) (xy 0.20701 0.05715)
						(xy 0.21209 0.04699) (xy 0.2159 0.03683) (xy 0.21844 0.02667) (xy 0.22225 0.01524) (xy 0.22352 0.00508)
						(xy 0.22606 -0.00508) (xy 0.22733 -0.01651) (xy 0.22733 -0.02667) (xy 0.2286 -0.0381) (xy 0.22733 -0.04953)
						(xy 0.22733 -0.05969) (xy 0.22606 -0.07112) (xy 0.22352 -0.08128) (xy 0.22225 -0.09144) (xy 0.21844 -0.10287)
						(xy 0.2159 -0.11303) (xy 0.21209 -0.12319) (xy 0.20701 -0.13335) (xy 0.2032 -0.14224) (xy 0.19812 -0.1524)
						(xy 0.17272 -0.18796) (xy 0.1651 -0.19558) (xy 0.1651 -0.7366) (xy 0.16256 -0.76835) (xy 0.1524 -0.8001)
						(xy 0.13716 -0.82804) (xy 0.11684 -0.85344) (xy 0.09144 -0.87376) (xy 0.0635 -0.889) (xy 0.03175 -0.89916)
					)
					(width 0)
					(fill yes)
				)
			)
		)
		(pad "20" smd custom
			(at -25.94991 4.100068)
			(size 0.1143 0.1143)
			(layers "B.Cu" "B.Mask" "B.Paste")
			(net "GND")
			(options
				(clearance outline)
				(anchor circle)
			)
			(primitives
				(gr_poly
					(pts
						(xy 0 -0.9017) (xy -0.03175 -0.89916) (xy -0.0635 -0.889) (xy -0.09144 -0.87376) (xy -0.11684 -0.85344)
						(xy -0.13716 -0.82804) (xy -0.1524 -0.8001) (xy -0.16256 -0.76835) (xy -0.1651 -0.7366) (xy -0.1651 -0.11938)
						(xy -0.17272 -0.11176) (xy -0.19812 -0.0762) (xy -0.2032 -0.06604) (xy -0.20701 -0.05715) (xy -0.21209 -0.04699)
						(xy -0.2159 -0.03683) (xy -0.21844 -0.02667) (xy -0.22225 -0.01524) (xy -0.22352 -0.00508) (xy -0.22606 0.00508)
						(xy -0.22733 0.01651) (xy -0.22733 0.02667) (xy -0.2286 0.0381) (xy -0.22733 0.04953) (xy -0.22733 0.05969)
						(xy -0.22606 0.07112) (xy -0.22352 0.08128) (xy -0.22225 0.09144) (xy -0.21844 0.10287) (xy -0.2159 0.11303)
						(xy -0.21209 0.12319) (xy -0.20701 0.13335) (xy -0.2032 0.14224) (xy -0.19812 0.1524) (xy -0.17272 0.18796)
						(xy -0.1651 0.19558) (xy -0.1651 0.7366) (xy -0.16256 0.76835) (xy -0.1524 0.8001) (xy -0.13716 0.82804)
						(xy -0.11684 0.85344) (xy -0.09144 0.87376) (xy -0.0635 0.889) (xy -0.03175 0.89916) (xy 0 0.9017)
						(xy 0.03175 0.89916) (xy 0.0635 0.889) (xy 0.09144 0.87376) (xy 0.11684 0.85344) (xy 0.13716 0.82804)
						(xy 0.1524 0.8001) (xy 0.16256 0.76835) (xy 0.1651 0.7366) (xy 0.1651 0.19685) (xy 0.17272 0.18923)
						(xy 0.17907 0.18034) (xy 0.18669 0.17145) (xy 0.19177 0.16256) (xy 0.19812 0.15367) (xy 0.20828 0.13335)
						(xy 0.21971 0.10287) (xy 0.22225 0.09271) (xy 0.22479 0.08128) (xy 0.22606 0.07112) (xy 0.2286 0.05969)
						(xy 0.2286 0.01651) (xy 0.22606 0.00508) (xy 0.22479 -0.00508) (xy 0.22225 -0.01651) (xy 0.21971 -0.02667)
						(xy 0.20828 -0.05715) (xy 0.19812 -0.07747) (xy 0.19177 -0.08636) (xy 0.18669 -0.09525) (xy 0.17907 -0.10414)
						(xy 0.17272 -0.11303) (xy 0.1651 -0.12065) (xy 0.1651 -0.7366) (xy 0.16256 -0.76835) (xy 0.1524 -0.8001)
						(xy 0.13716 -0.82804) (xy 0.11684 -0.85344) (xy 0.09144 -0.87376) (xy 0.0635 -0.889) (xy 0.03175 -0.89916)
					)
					(width 0)
					(fill yes)
				)
			)
		)
	)
)
